# T6G (Grand Teton) — schematic netlist excerpt (pin names and nets, part order shuffled) for the footprints in the layout excerpt that follows; sources: Cadence DE-HDL packaged netlist, KiCad conversion of 04192023_DAF0TMB3IC0_F0TG_MB_C_brd_V02_OCP.brd

C2505  Q_CAP  22UF 4V 20% X6S  pkg C0402  page 74 : A = PVDD11_S3_P1 ; B = GND
C6564  Q_CAP_DIFFBUS  DIFF BUS_0.22UF 6.3V 20% X6S  pkg C0201  page 286 : \1\ = P5E_CPU0_P1_TX_BUF_C_DN<15> ; \2\ = P5E_CPU0_P1_TX_BUF_DN<15>
C2476  Q_CAP  22UF 4V 20% X6S  pkg C0402  page 74 : A = PVDDCR_SOC_P1 ; B = GND

(kicad_pcb
	(version 20260206)
	(generator "pcbnew")
	(generator_version "10.0")
	(general
		(thickness 1.6)
		(legacy_teardrops no)
	)
	(paper "A4")
	(title_block
		(title "04192023_DAF0TMB3IC0_F0TG_MB_C_brd_V02_OCP.brd")
		(comment 1 "Grand Teton / footprints 5722-5724 of 8354")
	)
	(layers
		(0 "F.Cu" signal "TOP")
		(4 "In1.Cu" signal "GND")
		(6 "In2.Cu" signal "IN1")
		(8 "In3.Cu" signal "GND1")
		(10 "In4.Cu" signal "IN2")
		(12 "In5.Cu" signal "GND2")
		(14 "In6.Cu" signal "IN3")
		(16 "In7.Cu" signal "GND3")
		(18 "In8.Cu" signal "VCC")
		(20 "In9.Cu" signal "VCC1")
		(22 "In10.Cu" signal "GND4")
		(24 "In11.Cu" signal "IN4")
		(26 "In12.Cu" signal "GND5")
		(28 "In13.Cu" signal "IN5")
		(30 "In14.Cu" signal "GND6")
		(32 "In15.Cu" signal "IN6")
		(34 "In16.Cu" signal "GND7")
		(2 "B.Cu" signal "BOTTOM")
		(9 "F.Adhes" user "F.Adhesive")
		(11 "B.Adhes" user "B.Adhesive")
		(13 "F.Paste" user "Package Geometry/Pastemask Top")
		(15 "B.Paste" user "Package Geometry/Pastemask Bottom")
		(5 "F.SilkS" user "Ref Des/Silkscreen Top")
		(7 "B.SilkS" user "Ref Des/Silkscreen Bottom")
		(1 "F.Mask" user "Board Geometry/Soldermask Top")
		(3 "B.Mask" user "Board Geometry/Soldermask Bottom")
		(17 "Dwgs.User" user "User.Drawings")
		(19 "Cmts.User" user "User.Comments")
		(21 "Eco1.User" user "User.Eco1")
		(23 "Eco2.User" user "User.Eco2")
		(25 "Edge.Cuts" user "Board Geometry/Outline")
		(27 "Margin" user)
		(31 "F.CrtYd" user "Package Geometry/Place Bound Top")
		(29 "B.CrtYd" user "Package Geometry/Place Bound Bottom")
		(35 "F.Fab" user "Ref Des/Assembly Top")
		(33 "B.Fab" user "Ref Des/Assembly Bottom")
	)
	(footprint ""
		(layer "B.Cu")
		(at 113.105946 -259.845302 180)
		(property "Reference" "C2505"
			(at 0 0 0)
			(layer "B.SilkS")
			(hide yes)
			(effects
				(font
					(size 1.27 1.27)
				)
				(justify mirror)
			)
		)
		(property "Value" ""
			(at 0 0 0)
			(layer "B.Fab")
			(effects
				(font
					(size 1.27 1.27)
				)
				(justify mirror)
			)
		)
		(duplicate_pad_numbers_are_jumpers no)
		(fp_line
			(start 0.7874 0.4064)
			(end 0.7874 -0.4064)
			(stroke
				(width 0.1524)
				(type default)
			)
			(layer "B.SilkS")
		)
		(fp_line
			(start 0.7874 -0.4064)
			(end -0.7874 -0.4064)
			(stroke
				(width 0.1524)
				(type default)
			)
			(layer "B.SilkS")
		)
		(fp_line
			(start -0.7874 0.4064)
			(end 0.7874 0.4064)
			(stroke
				(width 0.1524)
				(type default)
			)
			(layer "B.SilkS")
		)
		(fp_line
			(start -0.7874 -0.4064)
			(end -0.7874 0.4064)
			(stroke
				(width 0.1524)
				(type default)
			)
			(layer "B.SilkS")
		)
		(fp_line
			(start 0.67945 0.3048)
			(end 0.67945 -0.305054)
			(stroke
				(width 0.1)
				(type default)
			)
			(layer "B.Fab")
		)
		(fp_line
			(start 0.67945 -0.305054)
			(end 0.12065 -0.305054)
			(stroke
				(width 0.1)
				(type default)
			)
			(layer "B.Fab")
		)
		(fp_line
			(start 0.12065 0.3048)
			(end 0.67945 0.3048)
			(stroke
				(width 0.1)
				(type default)
			)
			(layer "B.Fab")
		)
		(fp_line
			(start 0.12065 0.2794)
			(end 0.12065 0.3048)
			(stroke
				(width 0.1)
				(type default)
			)
			(layer "B.Fab")
		)
		(fp_line
			(start 0.12065 -0.2794)
			(end -0.12065 -0.2794)
			(stroke
				(width 0.1)
				(type default)
			)
			(layer "B.Fab")
		)
		(fp_line
			(start 0.12065 -0.305054)
			(end 0.12065 -0.2794)
			(stroke
				(width 0.1)
				(type default)
			)
			(layer "B.Fab")
		)
		(fp_line
			(start -0.120396 0.3048)
			(end -0.120396 0.2794)
			(stroke
				(width 0.1)
				(type default)
			)
			(layer "B.Fab")
		)
		(fp_line
			(start -0.120396 0.2794)
			(end 0.12065 0.2794)
			(stroke
				(width 0.1)
				(type default)
			)
			(layer "B.Fab")
		)
		(fp_line
			(start -0.12065 -0.2794)
			(end -0.12065 -0.3048)
			(stroke
				(width 0.1)
				(type default)
			)
			(layer "B.Fab")
		)
		(fp_line
			(start -0.12065 -0.3048)
			(end -0.67945 -0.3048)
			(stroke
				(width 0.1)
				(type default)
			)
			(layer "B.Fab")
		)
		(fp_line
			(start -0.67945 0.3048)
			(end -0.120396 0.3048)
			(stroke
				(width 0.1)
				(type default)
			)
			(layer "B.Fab")
		)
		(fp_line
			(start -0.67945 -0.3048)
			(end -0.67945 0.3048)
			(stroke
				(width 0.1)
				(type default)
			)
			(layer "B.Fab")
		)
		(pad "1" smd circle
			(at 0.40005 0)
			(size 0 0)
			(layers "B.Cu" "B.Mask" "B.Paste")
			(net "PVDD11_S3_P1")
		)
		(pad "2" smd circle
			(at -0.40005 0)
			(size 0 0)
			(layers "B.Cu" "B.Mask" "B.Paste")
			(net "GND")
		)
	)
	(footprint ""
		(layer "B.Cu")
		(at 117.895624 -258.405376)
		(property "Reference" "C2476"
			(at 0 0 0)
			(layer "B.SilkS")
			(hide yes)
			(effects
				(font
					(size 1.27 1.27)
				)
				(justify mirror)
			)
		)
		(property "Value" ""
			(at 0 0 0)
			(layer "B.Fab")
			(effects
				(font
					(size 1.27 1.27)
				)
				(justify mirror)
			)
		)
		(duplicate_pad_numbers_are_jumpers no)
		(fp_line
			(start -0.7874 -0.4064)
			(end -0.7874 0.4064)
			(stroke
				(width 0.1524)
				(type default)
			)
			(layer "B.SilkS")
		)
		(fp_line
			(start -0.7874 0.4064)
			(end 0.7874 0.4064)
			(stroke
				(width 0.1524)
				(type default)
			)
			(layer "B.SilkS")
		)
		(fp_line
			(start 0.7874 -0.4064)
			(end -0.7874 -0.4064)
			(stroke
				(width 0.1524)
				(type default)
			)
			(layer "B.SilkS")
		)
		(fp_line
			(start 0.7874 0.4064)
			(end 0.7874 -0.4064)
			(stroke
				(width 0.1524)
				(type default)
			)
			(layer "B.SilkS")
		)
		(fp_line
			(start -0.67945 -0.3048)
			(end -0.67945 0.3048)
			(stroke
				(width 0.1)
				(type default)
			)
			(layer "B.Fab")
		)
		(fp_line
			(start -0.67945 0.3048)
			(end -0.120396 0.3048)
			(stroke
				(width 0.1)
				(type default)
			)
			(layer "B.Fab")
		)
		(fp_line
			(start -0.12065 -0.3048)
			(end -0.67945 -0.3048)
			(stroke
				(width 0.1)
				(type default)
			)
			(layer "B.Fab")
		)
		(fp_line
			(start -0.12065 -0.2794)
			(end -0.12065 -0.3048)
			(stroke
				(width 0.1)
				(type default)
			)
			(layer "B.Fab")
		)
		(fp_line
			(start -0.120396 0.2794)
			(end 0.12065 0.2794)
			(stroke
				(width 0.1)
				(type default)
			)
			(layer "B.Fab")
		)
		(fp_line
			(start -0.120396 0.3048)
			(end -0.120396 0.2794)
			(stroke
				(width 0.1)
				(type default)
			)
			(layer "B.Fab")
		)
		(fp_line
			(start 0.12065 -0.305054)
			(end 0.12065 -0.2794)
			(stroke
				(width 0.1)
				(type default)
			)
			(layer "B.Fab")
		)
		(fp_line
			(start 0.12065 -0.2794)
			(end -0.12065 -0.2794)
			(stroke
				(width 0.1)
				(type default)
			)
			(layer "B.Fab")
		)
		(fp_line
			(start 0.12065 0.2794)
			(end 0.12065 0.3048)
			(stroke
				(width 0.1)
				(type default)
			)
			(layer "B.Fab")
		)
		(fp_line
			(start 0.12065 0.3048)
			(end 0.67945 0.3048)
			(stroke
				(width 0.1)
				(type default)
			)
			(layer "B.Fab")
		)
		(fp_line
			(start 0.67945 -0.305054)
			(end 0.12065 -0.305054)
			(stroke
				(width 0.1)
				(type default)
			)
			(layer "B.Fab")
		)
		(fp_line
			(start 0.67945 0.3048)
			(end 0.67945 -0.305054)
			(stroke
				(width 0.1)
				(type default)
			)
			(layer "B.Fab")
		)
		(pad "1" smd circle
			(at 0.40005 0 180)
			(size 0 0)
			(layers "B.Cu" "B.Mask" "B.Paste")
			(net "PVDDCR_SOC_P1")
		)
		(pad "2" smd circle
			(at -0.40005 0 180)
			(size 0 0)
			(layers "B.Cu" "B.Mask" "B.Paste")
			(net "GND")
		)
	)
	(footprint ""
		(layer "B.Cu")
		(at 351.248726 -416.899344 90)
		(property "Reference" "C6564"
			(at 0 0 90)
			(layer "B.SilkS")
			(hide yes)
			(effects
				(font
					(size 1.27 1.27)
				)
				(justify mirror)
			)
		)
		(property "Value" ""
			(at 0 0 90)
			(layer "B.Fab")
			(effects
				(font
					(size 1.27 1.27)
				)
				(justify mirror)
			)
		)
		(duplicate_pad_numbers_are_jumpers no)
		(fp_line
			(start 0.299974 -0.150114)
			(end -0.299974 -0.150114)
			(stroke
				(width 0.1)
				(type default)
			)
			(layer "B.Fab")
		)
		(fp_line
			(start -0.299974 -0.150114)
			(end -0.299974 0.150114)
			(stroke
				(width 0.1)
				(type default)
			)
			(layer "B.Fab")
		)
		(fp_line
			(start 0.299974 0.150114)
			(end 0.299974 -0.150114)
			(stroke
				(width 0.1)
				(type default)
			)
			(layer "B.Fab")
		)
		(fp_line
			(start -0.299974 0.150114)
			(end 0.299974 0.150114)
			(stroke
				(width 0.1)
				(type default)
			)
			(layer "B.Fab")
		)
		(pad "1" smd rect
			(at 0.2667 0 270)
			(size 0.3048 0.381)
			(layers "B.Cu" "B.Mask" "B.Paste")
			(net "P5E_CPU0_P1_TX_BUF_C_DN<15>")
		)
		(pad "2" smd rect
			(at -0.2667 0 270)
			(size 0.3048 0.381)
			(layers "B.Cu" "B.Mask" "B.Paste")
			(net "P5E_CPU0_P1_TX_BUF_DN<15>")
		)
	)
)
